(kicad_pcb
	(version 20260206)
	(generator "pcbnew")
	(generator_version "10.0")
	(general
		(thickness 1.6)
		(legacy_teardrops no)
	)
	(paper "A4")
	(title_block
		(title "Bryce Canyon_F.DPB_16315-1-OCP.brd")
		(comment 1 "Bryce Canyon / footprints 1612-1619 of 2223")
	)
	(layers
		(0 "F.Cu" signal "TOP")
		(4 "In1.Cu" signal "L2GND")
		(6 "In2.Cu" signal "L3")
		(8 "In3.Cu" signal "L4GND")
		(10 "In4.Cu" signal "L5")
		(12 "In5.Cu" signal "L6VCC")
		(14 "In6.Cu" signal "L7VCC")
		(16 "In7.Cu" signal "L8")
		(18 "In8.Cu" signal "L9GND")
		(20 "In9.Cu" signal "L10")
		(22 "In10.Cu" signal "L11GND")
		(2 "B.Cu" signal "BOTTOM")
		(9 "F.Adhes" user "F.Adhesive")
		(11 "B.Adhes" user "B.Adhesive")
		(13 "F.Paste" user "Package Geometry/Pastemask Top")
		(15 "B.Paste" user "Package Geometry/Pastemask Bottom")
		(5 "F.SilkS" user "Ref Des/Silkscreen Top")
		(7 "B.SilkS" user "Ref Des/Silkscreen Bottom")
		(1 "F.Mask" user "Board Geometry/Soldermask Top")
		(3 "B.Mask" user "Board Geometry/Soldermask Bottom")
		(17 "Dwgs.User" user "User.Drawings")
		(19 "Cmts.User" user "User.Comments")
		(21 "Eco1.User" user "User.Eco1")
		(23 "Eco2.User" user "User.Eco2")
		(25 "Edge.Cuts" user "Board Geometry/Outline")
		(27 "Margin" user)
		(31 "F.CrtYd" user "Package Geometry/Place Bound Top")
		(29 "B.CrtYd" user "Package Geometry/Place Bound Bottom")
		(35 "F.Fab" user "Ref Des/Assembly Top")
		(33 "B.Fab" user "Ref Des/Assembly Bottom")
	)
	(footprint ""
		(layer "F.Cu")
		(at 377.915932 -139.13485 -90)
		(property "Reference" "U31"
			(at 0 0 270)
			(layer "F.SilkS")
			(hide yes)
			(effects
				(font
					(size 1.27 1.27)
				)
			)
		)
		(property "Value" "SN74LVC1G08DCKR-GP"
			(at -2.3368 -8.6868 270)
			(unlocked yes)
			(layer "F.Fab")
			(hide yes)
			(effects
				(font
					(size 1.016 1.016)
					(thickness 0.1524)
				)
			)
		)
		(property "Device Type" "SC70-5H44"
			(at -2.3114 -10.414 270)
			(unlocked yes)
			(layer "F.Fab")
			(hide yes)
			(effects
				(font
					(size 1.016 1.016)
					(thickness 0.1524)
				)
			)
		)
		(duplicate_pad_numbers_are_jumpers no)
		(fp_line
			(start -1.27 1.7018)
			(end -1.27 -1.7018)
			(stroke
				(width 0.1524)
				(type default)
			)
			(layer "F.SilkS")
		)
		(fp_line
			(start 1.27 1.7018)
			(end -1.27 1.7018)
			(stroke
				(width 0.1524)
				(type default)
			)
			(layer "F.SilkS")
		)
		(fp_line
			(start -1.27 -1.7018)
			(end 1.27 -1.7018)
			(stroke
				(width 0.1524)
				(type default)
			)
			(layer "F.SilkS")
		)
		(fp_line
			(start 1.27 -1.7018)
			(end 1.27 1.7018)
			(stroke
				(width 0.1524)
				(type default)
			)
			(layer "F.SilkS")
		)
		(fp_line
			(start 0.6604 -1.8034)
			(end 1.3843 -1.8034)
			(stroke
				(width 0.3302)
				(type default)
			)
			(layer "F.SilkS")
		)
		(fp_line
			(start 1.3843 -1.8034)
			(end 1.3843 -1.1176)
			(stroke
				(width 0.3302)
				(type default)
			)
			(layer "F.SilkS")
		)
		(fp_rect
			(start -1.524 1.9558)
			(end 1.524 -1.9558)
			(stroke
				(width 0)
				(type default)
			)
			(fill no)
			(layer "F.CrtYd")
		)
		(fp_poly
			(pts
				(xy -1.524 -1.9558) (xy 1.524 -1.9558) (xy 1.524 1.9558) (xy -1.524 1.9558)
			)
			(stroke
				(width 0)
				(type default)
			)
			(fill no)
			(layer "F.Fab")
		)
		(pad "1" smd rect
			(at 0.65024 -0.8255 270)
			(size 0.4064 1.2192)
			(layers "F.Cu" "F.Mask" "F.Paste")
			(net "P12V_B_PGOOD")
		)
		(pad "2" smd rect
			(at 0 -0.8255 270)
			(size 0.4064 1.2192)
			(layers "F.Cu" "F.Mask" "F.Paste")
			(net "COMP_B_PWR_EN")
		)
		(pad "3" smd rect
			(at -0.65024 -0.8255 270)
			(size 0.4064 1.2192)
			(layers "F.Cu" "F.Mask" "F.Paste")
			(net "GND")
		)
		(pad "4" smd rect
			(at -0.65024 0.8255 270)
			(size 0.4064 1.2192)
			(layers "F.Cu" "F.Mask" "F.Paste")
			(net "MB1_HS_ENABLE")
		)
		(pad "5" smd rect
			(at 0.65024 0.8255 270)
			(size 0.4064 1.2192)
			(layers "F.Cu" "F.Mask" "F.Paste")
			(net "P3V3_B_BIAS")
		)
	)
	(footprint ""
		(layer "F.Cu")
		(at 427.009052 -295.826942 180)
		(property "Reference" "C158"
			(at 0 0 180)
			(layer "F.SilkS")
			(hide yes)
			(effects
				(font
					(size 1.27 1.27)
				)
			)
		)
		(property "Value" "SC10U16V6KX-2GP"
			(at -0.0762 -5.1308 180)
			(unlocked yes)
			(layer "F.Fab")
			(hide yes)
			(effects
				(font
					(size 1.016 1.016)
					(thickness 0.1524)
				)
			)
		)
		(property "Device Type" "C1206H71"
			(at -0.127 -6.6548 180)
			(unlocked yes)
			(layer "F.Fab")
			(hide yes)
			(effects
				(font
					(size 1.016 1.016)
					(thickness 0.1524)
				)
			)
		)
		(duplicate_pad_numbers_are_jumpers no)
		(fp_line
			(start 1.016 2.2352)
			(end -1.016 2.2352)
			(stroke
				(width 0.1524)
				(type default)
			)
			(layer "F.SilkS")
		)
		(fp_line
			(start 1.016 0.8382)
			(end 1.016 2.2352)
			(stroke
				(width 0.1524)
				(type default)
			)
			(layer "F.SilkS")
		)
		(fp_line
			(start 1.016 -2.2352)
			(end 1.016 -0.8382)
			(stroke
				(width 0.1524)
				(type default)
			)
			(layer "F.SilkS")
		)
		(fp_line
			(start -1.016 2.2352)
			(end -1.016 0.8382)
			(stroke
				(width 0.1524)
				(type default)
			)
			(layer "F.SilkS")
		)
		(fp_line
			(start -1.016 -0.8382)
			(end -1.016 -2.2352)
			(stroke
				(width 0.1524)
				(type default)
			)
			(layer "F.SilkS")
		)
		(fp_line
			(start -1.016 -2.2352)
			(end 1.016 -2.2352)
			(stroke
				(width 0.1524)
				(type default)
			)
			(layer "F.SilkS")
		)
		(fp_rect
			(start -1.0922 2.3114)
			(end 1.0922 -2.3114)
			(stroke
				(width 0)
				(type default)
			)
			(fill no)
			(layer "F.CrtYd")
		)
		(fp_poly
			(pts
				(xy 1.0922 -2.3114) (xy 1.0922 2.3114) (xy -1.0922 2.3114) (xy -1.0922 -2.3114)
			)
			(stroke
				(width 0)
				(type default)
			)
			(fill no)
			(layer "F.Fab")
		)
		(pad "1" smd rect
			(at 0 -1.397 180)
			(size 1.651 1.27)
			(layers "F.Cu" "F.Mask" "F.Paste")
			(net "P5V_HDD9")
		)
		(pad "2" smd rect
			(at 0 1.397 180)
			(size 1.651 1.27)
			(layers "F.Cu" "F.Mask" "F.Paste")
			(net "GND")
		)
	)
	(footprint ""
		(layer "F.Cu")
		(at 444.7286 -68.707)
		(property "Reference" "TP172"
			(at 0 0 0)
			(layer "F.SilkS")
			(hide yes)
			(effects
				(font
					(size 1.27 1.27)
				)
			)
		)
		(property "Value" "TPAD32-GP"
			(at -0.0508 -1.6764 0)
			(unlocked yes)
			(layer "F.Fab")
			(hide yes)
			(effects
				(font
					(size 1.016 1.016)
					(thickness 0.1524)
				)
			)
		)
		(property "Device Type" "TPAD32"
			(at -0.0508 -3.2004 0)
			(unlocked yes)
			(layer "F.Fab")
			(hide yes)
			(effects
				(font
					(size 1.016 1.016)
					(thickness 0.1524)
				)
			)
		)
		(duplicate_pad_numbers_are_jumpers no)
		(fp_poly
			(pts
				(arc
					(start 0.4064 0)
					(mid -0.4064 0)
					(end 0.4064 0)
				)
			)
			(stroke
				(width 0)
				(type default)
			)
			(fill no)
			(layer "F.CrtYd")
		)
		(fp_poly
			(pts
				(arc
					(start 0.7112 0)
					(mid -0.7112 0)
					(end 0.7112 0)
				)
			)
			(stroke
				(width 0)
				(type default)
			)
			(fill no)
			(layer "F.Fab")
		)
		(pad "1" smd circle
			(at 0 0)
			(size 0.8128 0.8128)
			(layers "F.Cu" "F.Mask" "F.Paste")
			(net "ACT_HDD_34")
		)
	)
	(footprint ""
		(layer "F.Cu")
		(at 247.79097 -296.901362 180)
		(property "Reference" "U47"
			(at 0 0 180)
			(layer "F.SilkS")
			(hide yes)
			(effects
				(font
					(size 1.27 1.27)
				)
			)
		)
		(property "Value" "SN74LVC1G08DCKR-GP"
			(at -2.3368 -8.6868 180)
			(unlocked yes)
			(layer "F.Fab")
			(hide yes)
			(effects
				(font
					(size 1.016 1.016)
					(thickness 0.1524)
				)
			)
		)
		(property "Device Type" "SC70-5H44"
			(at -2.3114 -10.414 180)
			(unlocked yes)
			(layer "F.Fab")
			(hide yes)
			(effects
				(font
					(size 1.016 1.016)
					(thickness 0.1524)
				)
			)
		)
		(duplicate_pad_numbers_are_jumpers no)
		(fp_line
			(start 1.3843 -1.8034)
			(end 1.3843 -1.1176)
			(stroke
				(width 0.3302)
				(type default)
			)
			(layer "F.SilkS")
		)
		(fp_line
			(start 1.27 1.7018)
			(end -1.27 1.7018)
			(stroke
				(width 0.1524)
				(type default)
			)
			(layer "F.SilkS")
		)
		(fp_line
			(start 1.27 -1.7018)
			(end 1.27 1.7018)
			(stroke
				(width 0.1524)
				(type default)
			)
			(layer "F.SilkS")
		)
		(fp_line
			(start 0.6604 -1.8034)
			(end 1.3843 -1.8034)
			(stroke
				(width 0.3302)
				(type default)
			)
			(layer "F.SilkS")
		)
		(fp_line
			(start -1.27 1.7018)
			(end -1.27 -1.7018)
			(stroke
				(width 0.1524)
				(type default)
			)
			(layer "F.SilkS")
		)
		(fp_line
			(start -1.27 -1.7018)
			(end 1.27 -1.7018)
			(stroke
				(width 0.1524)
				(type default)
			)
			(layer "F.SilkS")
		)
		(fp_rect
			(start -1.524 1.9558)
			(end 1.524 -1.9558)
			(stroke
				(width 0)
				(type default)
			)
			(fill no)
			(layer "F.CrtYd")
		)
		(fp_poly
			(pts
				(xy -1.524 -1.9558) (xy 1.524 -1.9558) (xy 1.524 1.9558) (xy -1.524 1.9558)
			)
			(stroke
				(width 0)
				(type default)
			)
			(fill no)
			(layer "F.Fab")
		)
		(pad "1" smd rect
			(at 0.65024 -0.8255 180)
			(size 0.4064 1.2192)
			(layers "F.Cu" "F.Mask" "F.Paste")
			(net "BMC_A_TO_EXP_A_RESET_N")
		)
		(pad "2" smd rect
			(at 0 -0.8255 180)
			(size 0.4064 1.2192)
			(layers "F.Cu" "F.Mask" "F.Paste")
			(net "RST_BTN_A_N")
		)
		(pad "3" smd rect
			(at -0.65024 -0.8255 180)
			(size 0.4064 1.2192)
			(layers "F.Cu" "F.Mask" "F.Paste")
			(net "GND")
		)
		(pad "4" smd rect
			(at -0.65024 0.8255 180)
			(size 0.4064 1.2192)
			(layers "F.Cu" "F.Mask" "F.Paste")
			(net "SCC_A_RESET_N")
		)
		(pad "5" smd rect
			(at 0.65024 0.8255 180)
			(size 0.4064 1.2192)
			(layers "F.Cu" "F.Mask" "F.Paste")
			(net "P3V3_STBY_A")
		)
	)
	(footprint ""
		(layer "F.Cu")
		(at 441.484512 -159.219392 -90)
		(property "Reference" "C324"
			(at 0 0 270)
			(layer "F.SilkS")
			(hide yes)
			(effects
				(font
					(size 1.27 1.27)
				)
			)
		)
		(property "Value" "SCD01U16V1KX-GP"
			(at -2.8321 -1.7399 270)
			(unlocked yes)
			(layer "F.Fab")
			(hide yes)
			(effects
				(font
					(size 1.016 1.016)
					(thickness 0.1524)
				)
			)
		)
		(property "Device Type" "C0201H13"
			(at -2.8321 -3.2639 270)
			(unlocked yes)
			(layer "F.Fab")
			(hide yes)
			(effects
				(font
					(size 1.016 1.016)
					(thickness 0.1524)
				)
			)
		)
		(duplicate_pad_numbers_are_jumpers no)
		(fp_rect
			(start -0.2794 0.6477)
			(end 0.2794 -0.6477)
			(stroke
				(width 0)
				(type default)
			)
			(fill no)
			(layer "F.CrtYd")
		)
		(fp_rect
			(start -0.2794 0.6477)
			(end 0.2794 -0.6477)
			(stroke
				(width 0)
				(type default)
			)
			(fill no)
			(layer "F.Fab")
		)
		(pad "1" smd custom
			(at 0 -0.2794 270)
			(size 0.0762 0.0762)
			(layers "F.Cu" "F.Mask" "F.Paste")
			(net "SAS_HDD_RX_N22")
			(options
				(clearance outline)
				(anchor circle)
			)
			(primitives
				(gr_poly
					(pts
						(arc
							(start 0.1524 -0.127)
							(mid 0.137521 -0.162921)
							(end 0.1016 -0.1778)
						)
						(arc
							(start -0.1016 -0.1778)
							(mid -0.137521 -0.162921)
							(end -0.1524 -0.127)
						)
						(arc
							(start -0.1524 0.127)
							(mid -0.137521 0.162921)
							(end -0.1016 0.1778)
						)
						(arc
							(start 0.1016 0.1778)
							(mid 0.137521 0.162921)
							(end 0.1524 0.127)
						)
					)
					(width 0)
					(fill yes)
				)
			)
		)
		(pad "2" smd custom
			(at 0 0.2794 270)
			(size 0.0762 0.0762)
			(layers "F.Cu" "F.Mask" "F.Paste")
			(net "PHY_SCC_A_TO_DRV_A_22_DN")
			(options
				(clearance outline)
				(anchor circle)
			)
			(primitives
				(gr_poly
					(pts
						(arc
							(start 0.1524 -0.127)
							(mid 0.137521 -0.162921)
							(end 0.1016 -0.1778)
						)
						(arc
							(start -0.1016 -0.1778)
							(mid -0.137521 -0.162921)
							(end -0.1524 -0.127)
						)
						(arc
							(start -0.1524 0.127)
							(mid -0.137521 0.162921)
							(end -0.1016 0.1778)
						)
						(arc
							(start 0.1016 0.1778)
							(mid 0.137521 0.162921)
							(end 0.1524 0.127)
						)
					)
					(width 0)
					(fill yes)
				)
			)
		)
	)
	(footprint ""
		(layer "F.Cu")
		(at 332.105 -42.585894)
		(property "Reference" "R833"
			(at 0 0 0)
			(layer "F.SilkS")
			(hide yes)
			(effects
				(font
					(size 1.27 1.27)
				)
			)
		)
		(property "Value" "4K7R2J-2-GP"
			(at 0.064008 -3.993896 0)
			(unlocked yes)
			(layer "F.Fab")
			(hide yes)
			(effects
				(font
					(size 1.016 1.016)
					(thickness 0.1524)
				)
			)
		)
		(property "Device Type" "R402H16"
			(at 0.064008 -5.517896 0)
			(unlocked yes)
			(layer "F.Fab")
			(hide yes)
			(effects
				(font
					(size 1.016 1.016)
					(thickness 0.1524)
				)
			)
		)
		(duplicate_pad_numbers_are_jumpers no)
		(fp_line
			(start -0.508 -0.9398)
			(end -0.508 0.9398)
			(stroke
				(width 0.1524)
				(type default)
			)
			(layer "F.SilkS")
		)
		(fp_line
			(start 0.508 -0.9398)
			(end -0.508 -0.9398)
			(stroke
				(width 0.1524)
				(type default)
			)
			(layer "F.SilkS")
		)
		(fp_rect
			(start -0.508 0.9398)
			(end 0.508 -0.9398)
			(stroke
				(width 0)
				(type default)
			)
			(fill no)
			(layer "F.CrtYd")
		)
		(fp_rect
			(start -0.508 0.9398)
			(end 0.508 -0.9398)
			(stroke
				(width 0)
				(type default)
			)
			(fill no)
			(layer "F.Fab")
		)
		(pad "1" smd custom
			(at 0 -0.4445)
			(size 0.1397 0.1397)
			(layers "F.Cu" "F.Mask" "F.Paste")
			(net "SW_PWR_R_HDD30")
			(options
				(clearance outline)
				(anchor circle)
			)
			(primitives
				(gr_poly
					(pts
						(arc
							(start -0.1778 -0.2794)
							(mid -0.249642 -0.249642)
							(end -0.2794 -0.1778)
						)
						(arc
							(start -0.2794 0.1778)
							(mid -0.249642 0.249642)
							(end -0.1778 0.2794)
						)
						(arc
							(start 0.1778 0.2794)
							(mid 0.249642 0.249642)
							(end 0.2794 0.1778)
						)
						(arc
							(start 0.2794 -0.1778)
							(mid 0.249642 -0.249642)
							(end 0.1778 -0.2794)
						)
					)
					(width 0)
					(fill yes)
				)
			)
		)
		(pad "2" smd custom
			(at 0 0.4445)
			(size 0.1397 0.1397)
			(layers "F.Cu" "F.Mask" "F.Paste")
			(net "GND")
			(options
				(clearance outline)
				(anchor circle)
			)
			(primitives
				(gr_poly
					(pts
						(arc
							(start -0.1778 -0.2794)
							(mid -0.249642 -0.249642)
							(end -0.2794 -0.1778)
						)
						(arc
							(start -0.2794 0.1778)
							(mid -0.249642 0.249642)
							(end -0.1778 0.2794)
						)
						(arc
							(start 0.1778 0.2794)
							(mid 0.249642 0.249642)
							(end 0.2794 0.1778)
						)
						(arc
							(start 0.2794 -0.1778)
							(mid 0.249642 -0.249642)
							(end 0.1778 -0.2794)
						)
					)
					(width 0)
					(fill yes)
				)
			)
		)
	)
	(footprint ""
		(layer "F.Cu")
		(at 262.69442 -212.046566 -90)
		(property "Reference" "C115"
			(at 0 0 270)
			(layer "F.SilkS")
			(hide yes)
			(effects
				(font
					(size 1.27 1.27)
				)
			)
		)
		(property "Value" "SCD1U16V2KX-3GP"
			(at 1.1811 -2.7051 270)
			(unlocked yes)
			(layer "F.Fab")
			(hide yes)
			(effects
				(font
					(size 1.016 1.016)
					(thickness 0.1524)
				)
			)
		)
		(property "Device Type" "C402H22"
			(at 1.1811 -4.2291 270)
			(unlocked yes)
			(layer "F.Fab")
			(hide yes)
			(effects
				(font
					(size 1.016 1.016)
					(thickness 0.1524)
				)
			)
		)
		(duplicate_pad_numbers_are_jumpers no)
		(fp_rect
			(start -0.4318 0.9525)
			(end 0.4318 -0.9525)
			(stroke
				(width 0)
				(type default)
			)
			(fill no)
			(layer "F.CrtYd")
		)
		(fp_rect
			(start -0.4318 0.9525)
			(end 0.4318 -0.9525)
			(stroke
				(width 0)
				(type default)
			)
			(fill no)
			(layer "F.Fab")
		)
		(pad "1" smd custom
			(at 0 -0.4445 270)
			(size 0.1524 0.1524)
			(layers "F.Cu" "F.Mask" "F.Paste")
			(net "I2C_DPB_BUFF_EN")
			(options
				(clearance outline)
				(anchor circle)
			)
			(primitives
				(gr_poly
					(pts
						(arc
							(start 0.3048 -0.2032)
							(mid 0.275042 -0.275042)
							(end 0.2032 -0.3048)
						)
						(arc
							(start -0.2032 -0.3048)
							(mid -0.275042 -0.275042)
							(end -0.3048 -0.2032)
						)
						(arc
							(start -0.3048 0.2032)
							(mid -0.275042 0.275042)
							(end -0.2032 0.3048)
						)
						(arc
							(start 0.2032 0.3048)
							(mid 0.275042 0.275042)
							(end 0.3048 0.2032)
						)
					)
					(width 0)
					(fill yes)
				)
			)
		)
		(pad "2" smd custom
			(at 0 0.4445 270)
			(size 0.1524 0.1524)
			(layers "F.Cu" "F.Mask" "F.Paste")
			(net "GND")
			(options
				(clearance outline)
				(anchor circle)
			)
			(primitives
				(gr_poly
					(pts
						(arc
							(start 0.3048 -0.2032)
							(mid 0.275042 -0.275042)
							(end 0.2032 -0.3048)
						)
						(arc
							(start -0.2032 -0.3048)
							(mid -0.275042 -0.275042)
							(end -0.3048 -0.2032)
						)
						(arc
							(start -0.3048 0.2032)
							(mid -0.275042 0.275042)
							(end -0.2032 0.3048)
						)
						(arc
							(start 0.2032 0.3048)
							(mid 0.275042 0.275042)
							(end 0.3048 0.2032)
						)
					)
					(width 0)
					(fill yes)
				)
			)
		)
	)
	(footprint ""
		(layer "F.Cu")
		(at 20.430998 -177.778918 -90)
		(property "Reference" "C196"
			(at 0 0 270)
			(layer "F.SilkS")
			(hide yes)
			(effects
				(font
					(size 1.27 1.27)
				)
			)
		)
		(property "Value" "SC1U16V3KX-5GP"
			(at 0 -2.8194 270)
			(unlocked yes)
			(layer "F.Fab")
			(hide yes)
			(effects
				(font
					(size 1.016 1.016)
					(thickness 0.1524)
				)
			)
		)
		(property "Device Type" "C603H36"
			(at 0 -4.3434 270)
			(unlocked yes)
			(layer "F.Fab")
			(hide yes)
			(effects
				(font
					(size 1.016 1.016)
					(thickness 0.1524)
				)
			)
		)
		(duplicate_pad_numbers_are_jumpers no)
		(fp_line
			(start 0.508 0)
			(end -0.508 0)
			(stroke
				(width 0.2032)
				(type default)
			)
			(layer "F.SilkS")
		)
		(fp_rect
			(start -0.5842 1.3335)
			(end 0.5842 -1.3335)
			(stroke
				(width 0)
				(type default)
			)
			(fill no)
			(layer "F.CrtYd")
		)
		(fp_rect
			(start -0.5842 1.3335)
			(end 0.5842 -1.3335)
			(stroke
				(width 0)
				(type default)
			)
			(fill no)
			(layer "F.Fab")
		)
		(pad "1" smd custom
			(at 0 -0.762 270)
			(size 0.2159 0.2159)
			(layers "F.Cu" "F.Mask" "F.Paste")
			(net "P5V_HDD12")
			(options
				(clearance outline)
				(anchor circle)
			)
			(primitives
				(gr_poly
					(pts
						(arc
							(start -0.3302 -0.4318)
							(mid -0.402042 -0.402042)
							(end -0.4318 -0.3302)
						)
						(arc
							(start -0.4318 0.3302)
							(mid -0.402042 0.402042)
							(end -0.3302 0.4318)
						)
						(arc
							(start 0.3302 0.4318)
							(mid 0.402042 0.402042)
							(end 0.4318 0.3302)
						)
						(arc
							(start 0.4318 -0.3302)
							(mid 0.402042 -0.402042)
							(end 0.3302 -0.4318)
						)
					)
					(width 0)
					(fill yes)
				)
			)
		)
		(pad "2" smd custom
			(at 0 0.762 270)
			(size 0.2159 0.2159)
			(layers "F.Cu" "F.Mask" "F.Paste")
			(net "GND")
			(options
				(clearance outline)
				(anchor circle)
			)
			(primitives
				(gr_poly
					(pts
						(arc
							(start -0.3302 -0.4318)
							(mid -0.402042 -0.402042)
							(end -0.4318 -0.3302)
						)
						(arc
							(start -0.4318 0.3302)
							(mid -0.402042 0.402042)
							(end -0.3302 0.4318)
						)
						(arc
							(start 0.3302 0.4318)
							(mid 0.402042 0.402042)
							(end 0.4318 0.3302)
						)
						(arc
							(start 0.4318 -0.3302)
							(mid 0.402042 -0.402042)
							(end 0.3302 -0.4318)
						)
					)
					(width 0)
					(fill yes)
				)
			)
		)
	)
)
